FILE_TYPE = CONNECTIVITY;
{Allegro Design Entry HDL 16.6-p007 (v16-6-112F) 10/10/2012}
"PAGE_NUMBER" = 256;
0"NC";
END.
